# S9S_MB_2U (Grand Teton) — schematic netlist excerpt (pin names and nets, part order shuffled) for the footprints in the layout excerpt that follows; sources: Cadence DE-HDL packaged netlist, KiCad conversion of 03242023_DA0F0TMBIJ0_F0T_Motherboard_J_brd_V01_OCP.brd

R3226  Q_RES  2.2K 5% EMPTY  pkg 0402LF  page 241 : A = SMB_1_BMC_GPU_SCL ; B = P3V3_AUX
PC567  Q_CAP  22UF 16V 20% X6S  pkg C0805  page 259 : A = SW_P3V3_AUX_FLT ; B = GND
R2841  Q_RES  4.7K 5% CHIP  pkg 0402LF  page 148 : A = P3V3_AUX ; B = FM_SWB_PWRGD_N

(kicad_pcb
	(version 20260206)
	(generator "pcbnew")
	(generator_version "10.0")
	(general
		(thickness 1.6)
		(legacy_teardrops no)
	)
	(paper "A4")
	(title_block
		(title "03242023_DA0F0TMBIJ0_F0T_Motherboard_J_brd_V01_OCP.brd")
		(comment 1 "Grand Teton / footprints 281-283 of 6105")
	)
	(layers
		(0 "F.Cu" signal "TOP")
		(4 "In1.Cu" signal "GND")
		(6 "In2.Cu" signal "IN1")
		(8 "In3.Cu" signal "GND1")
		(10 "In4.Cu" signal "IN2")
		(12 "In5.Cu" signal "GND2")
		(14 "In6.Cu" signal "IN3")
		(16 "In7.Cu" signal "GND3")
		(18 "In8.Cu" signal "VCC")
		(20 "In9.Cu" signal "VCC1")
		(22 "In10.Cu" signal "GND4")
		(24 "In11.Cu" signal "IN4")
		(26 "In12.Cu" signal "GND5")
		(28 "In13.Cu" signal "IN5")
		(30 "In14.Cu" signal "GND6")
		(32 "In15.Cu" signal "IN6")
		(34 "In16.Cu" signal "GND7")
		(2 "B.Cu" signal "BOTTOM")
		(9 "F.Adhes" user "F.Adhesive")
		(11 "B.Adhes" user "B.Adhesive")
		(13 "F.Paste" user "Package Geometry/Pastemask Top")
		(15 "B.Paste" user "Package Geometry/Pastemask Bottom")
		(5 "F.SilkS" user "Ref Des/Silkscreen Top")
		(7 "B.SilkS" user "Ref Des/Silkscreen Bottom")
		(1 "F.Mask" user "Board Geometry/Soldermask Top")
		(3 "B.Mask" user "Board Geometry/Soldermask Bottom")
		(17 "Dwgs.User" user "User.Drawings")
		(19 "Cmts.User" user "User.Comments")
		(21 "Eco1.User" user "User.Eco1")
		(23 "Eco2.User" user "User.Eco2")
		(25 "Edge.Cuts" user "Board Geometry/Outline")
		(27 "Margin" user)
		(31 "F.CrtYd" user "Package Geometry/Place Bound Top")
		(29 "B.CrtYd" user "Package Geometry/Place Bound Bottom")
		(35 "F.Fab" user "Ref Des/Assembly Top")
		(33 "B.Fab" user "Ref Des/Assembly Bottom")
	)
	(footprint ""
		(layer "F.Cu")
		(at 431.989992 -386.171948 180)
		(property "Reference" "R2841"
			(at 0 0 180)
			(layer "F.SilkS")
			(hide yes)
			(effects
				(font
					(size 1.27 1.27)
				)
			)
		)
		(property "Value" ""
			(at 0 0 180)
			(layer "F.Fab")
			(effects
				(font
					(size 1.27 1.27)
				)
			)
		)
		(duplicate_pad_numbers_are_jumpers no)
		(fp_line
			(start 0.7874 0.4064)
			(end -0.7874 0.4064)
			(stroke
				(width 0.1524)
				(type default)
			)
			(layer "F.SilkS")
		)
		(fp_line
			(start 0.7874 -0.4064)
			(end 0.7874 0.4064)
			(stroke
				(width 0.1524)
				(type default)
			)
			(layer "F.SilkS")
		)
		(fp_line
			(start -0.7874 0.4064)
			(end -0.7874 -0.4064)
			(stroke
				(width 0.1524)
				(type default)
			)
			(layer "F.SilkS")
		)
		(fp_line
			(start -0.7874 -0.4064)
			(end 0.7874 -0.4064)
			(stroke
				(width 0.1524)
				(type default)
			)
			(layer "F.SilkS")
		)
		(fp_line
			(start 0.67945 0.3048)
			(end 0.120396 0.3048)
			(stroke
				(width 0.1)
				(type default)
			)
			(layer "F.Fab")
		)
		(fp_line
			(start 0.67945 -0.3048)
			(end 0.67945 0.3048)
			(stroke
				(width 0.1)
				(type default)
			)
			(layer "F.Fab")
		)
		(fp_line
			(start 0.12065 -0.2794)
			(end 0.12065 -0.3048)
			(stroke
				(width 0.1)
				(type default)
			)
			(layer "F.Fab")
		)
		(fp_line
			(start 0.12065 -0.3048)
			(end 0.67945 -0.3048)
			(stroke
				(width 0.1)
				(type default)
			)
			(layer "F.Fab")
		)
		(fp_line
			(start 0.120396 0.3048)
			(end 0.120396 0.2794)
			(stroke
				(width 0.1)
				(type default)
			)
			(layer "F.Fab")
		)
		(fp_line
			(start 0.120396 0.2794)
			(end -0.12065 0.2794)
			(stroke
				(width 0.1)
				(type default)
			)
			(layer "F.Fab")
		)
		(fp_line
			(start -0.12065 0.3048)
			(end -0.67945 0.3048)
			(stroke
				(width 0.1)
				(type default)
			)
			(layer "F.Fab")
		)
		(fp_line
			(start -0.12065 0.2794)
			(end -0.12065 0.3048)
			(stroke
				(width 0.1)
				(type default)
			)
			(layer "F.Fab")
		)
		(fp_line
			(start -0.12065 -0.2794)
			(end 0.12065 -0.2794)
			(stroke
				(width 0.1)
				(type default)
			)
			(layer "F.Fab")
		)
		(fp_line
			(start -0.12065 -0.305054)
			(end -0.12065 -0.2794)
			(stroke
				(width 0.1)
				(type default)
			)
			(layer "F.Fab")
		)
		(fp_line
			(start -0.67945 0.3048)
			(end -0.67945 -0.305054)
			(stroke
				(width 0.1)
				(type default)
			)
			(layer "F.Fab")
		)
		(fp_line
			(start -0.67945 -0.305054)
			(end -0.12065 -0.305054)
			(stroke
				(width 0.1)
				(type default)
			)
			(layer "F.Fab")
		)
		(pad "1" smd circle
			(at -0.40005 0 180)
			(size 0 0)
			(layers "F.Cu" "F.Mask" "F.Paste")
			(net "P3V3_AUX")
		)
		(pad "2" smd circle
			(at 0.40005 0 180)
			(size 0 0)
			(layers "F.Cu" "F.Mask" "F.Paste")
			(net "FM_SWB_PWRGD_N")
		)
	)
	(footprint ""
		(layer "F.Cu")
		(at 36.14928 -433.923948 180)
		(property "Reference" "R3226"
			(at 0 0 180)
			(layer "F.SilkS")
			(hide yes)
			(effects
				(font
					(size 1.27 1.27)
				)
			)
		)
		(property "Value" ""
			(at 0 0 180)
			(layer "F.Fab")
			(effects
				(font
					(size 1.27 1.27)
				)
			)
		)
		(duplicate_pad_numbers_are_jumpers no)
		(fp_line
			(start 0.7874 0.4064)
			(end -0.7874 0.4064)
			(stroke
				(width 0.1524)
				(type default)
			)
			(layer "F.SilkS")
		)
		(fp_line
			(start 0.7874 -0.4064)
			(end 0.7874 0.4064)
			(stroke
				(width 0.1524)
				(type default)
			)
			(layer "F.SilkS")
		)
		(fp_line
			(start -0.7874 0.4064)
			(end -0.7874 -0.4064)
			(stroke
				(width 0.1524)
				(type default)
			)
			(layer "F.SilkS")
		)
		(fp_line
			(start -0.7874 -0.4064)
			(end 0.7874 -0.4064)
			(stroke
				(width 0.1524)
				(type default)
			)
			(layer "F.SilkS")
		)
		(fp_line
			(start 0.67945 0.3048)
			(end 0.120396 0.3048)
			(stroke
				(width 0.1)
				(type default)
			)
			(layer "F.Fab")
		)
		(fp_line
			(start 0.67945 -0.3048)
			(end 0.67945 0.3048)
			(stroke
				(width 0.1)
				(type default)
			)
			(layer "F.Fab")
		)
		(fp_line
			(start 0.12065 -0.2794)
			(end 0.12065 -0.3048)
			(stroke
				(width 0.1)
				(type default)
			)
			(layer "F.Fab")
		)
		(fp_line
			(start 0.12065 -0.3048)
			(end 0.67945 -0.3048)
			(stroke
				(width 0.1)
				(type default)
			)
			(layer "F.Fab")
		)
		(fp_line
			(start 0.120396 0.3048)
			(end 0.120396 0.2794)
			(stroke
				(width 0.1)
				(type default)
			)
			(layer "F.Fab")
		)
		(fp_line
			(start 0.120396 0.2794)
			(end -0.12065 0.2794)
			(stroke
				(width 0.1)
				(type default)
			)
			(layer "F.Fab")
		)
		(fp_line
			(start -0.12065 0.3048)
			(end -0.67945 0.3048)
			(stroke
				(width 0.1)
				(type default)
			)
			(layer "F.Fab")
		)
		(fp_line
			(start -0.12065 0.2794)
			(end -0.12065 0.3048)
			(stroke
				(width 0.1)
				(type default)
			)
			(layer "F.Fab")
		)
		(fp_line
			(start -0.12065 -0.2794)
			(end 0.12065 -0.2794)
			(stroke
				(width 0.1)
				(type default)
			)
			(layer "F.Fab")
		)
		(fp_line
			(start -0.12065 -0.305054)
			(end -0.12065 -0.2794)
			(stroke
				(width 0.1)
				(type default)
			)
			(layer "F.Fab")
		)
		(fp_line
			(start -0.67945 0.3048)
			(end -0.67945 -0.305054)
			(stroke
				(width 0.1)
				(type default)
			)
			(layer "F.Fab")
		)
		(fp_line
			(start -0.67945 -0.305054)
			(end -0.12065 -0.305054)
			(stroke
				(width 0.1)
				(type default)
			)
			(layer "F.Fab")
		)
		(pad "1" smd circle
			(at -0.40005 0 180)
			(size 0 0)
			(layers "F.Cu" "F.Mask" "F.Paste")
			(net "SMB_1_BMC_GPU_SCL")
		)
		(pad "2" smd circle
			(at 0.40005 0 180)
			(size 0 0)
			(layers "F.Cu" "F.Mask" "F.Paste")
			(net "P3V3_AUX")
		)
	)
	(footprint ""
		(layer "F.Cu")
		(at 455.123804 -71.245984 -90)
		(property "Reference" "PC567"
			(at 0 0 270)
			(layer "F.SilkS")
			(hide yes)
			(effects
				(font
					(size 1.27 1.27)
				)
			)
		)
		(property "Value" ""
			(at 0 0 270)
			(layer "F.Fab")
			(effects
				(font
					(size 1.27 1.27)
				)
			)
		)
		(duplicate_pad_numbers_are_jumpers no)
		(fp_line
			(start -1.524 0.762)
			(end -1.524 -0.762)
			(stroke
				(width 0.1524)
				(type default)
			)
			(layer "F.SilkS")
		)
		(fp_line
			(start 1.524 0.762)
			(end -1.524 0.762)
			(stroke
				(width 0.1524)
				(type default)
			)
			(layer "F.SilkS")
		)
		(fp_line
			(start -1.524 -0.762)
			(end 1.524 -0.762)
			(stroke
				(width 0.1524)
				(type default)
			)
			(layer "F.SilkS")
		)
		(fp_line
			(start 1.524 -0.762)
			(end 1.524 0.762)
			(stroke
				(width 0.1524)
				(type default)
			)
			(layer "F.SilkS")
		)
		(fp_line
			(start -1.1049 0.724916)
			(end 1.1049 0.724916)
			(stroke
				(width 0.1)
				(type default)
			)
			(layer "F.Fab")
		)
		(fp_line
			(start 1.1049 0.724916)
			(end 1.1049 -0.724916)
			(stroke
				(width 0.1)
				(type default)
			)
			(layer "F.Fab")
		)
		(fp_line
			(start -1.1049 -0.724916)
			(end -1.1049 0.724916)
			(stroke
				(width 0.1)
				(type default)
			)
			(layer "F.Fab")
		)
		(fp_line
			(start 1.1049 -0.724916)
			(end -1.1049 -0.724916)
			(stroke
				(width 0.1)
				(type default)
			)
			(layer "F.Fab")
		)
		(pad "1" smd rect
			(at -0.889 0 90)
			(size 1.016 1.27)
			(layers "F.Cu" "F.Mask" "F.Paste")
			(net "SW_P3V3_AUX_FLT")
		)
		(pad "2" smd rect
			(at 0.889 0 90)
			(size 1.016 1.27)
			(layers "F.Cu" "F.Mask" "F.Paste")
			(net "GND")
		)
	)
)
